(kicad_pcb
	(version 20260206)
	(generator "pcbnew")
	(generator_version "10.0")
	(general
		(thickness 1.6)
		(legacy_teardrops no)
	)
	(paper "A4")
	(title_block
		(title "03242023_DA0F0TMBIJ0_F0T_Motherboard_J_brd_V01_OCP.brd")
		(comment 1 "Grand Teton / footprint 2414 of 6105 (J37), pads 1-109 of 175")
	)
	(layers
		(0 "F.Cu" signal "TOP")
		(4 "In1.Cu" signal "GND")
		(6 "In2.Cu" signal "IN1")
		(8 "In3.Cu" signal "GND1")
		(10 "In4.Cu" signal "IN2")
		(12 "In5.Cu" signal "GND2")
		(14 "In6.Cu" signal "IN3")
		(16 "In7.Cu" signal "GND3")
		(18 "In8.Cu" signal "VCC")
		(20 "In9.Cu" signal "VCC1")
		(22 "In10.Cu" signal "GND4")
		(24 "In11.Cu" signal "IN4")
		(26 "In12.Cu" signal "GND5")
		(28 "In13.Cu" signal "IN5")
		(30 "In14.Cu" signal "GND6")
		(32 "In15.Cu" signal "IN6")
		(34 "In16.Cu" signal "GND7")
		(2 "B.Cu" signal "BOTTOM")
		(9 "F.Adhes" user "F.Adhesive")
		(11 "B.Adhes" user "B.Adhesive")
		(13 "F.Paste" user "Package Geometry/Pastemask Top")
		(15 "B.Paste" user "Package Geometry/Pastemask Bottom")
		(5 "F.SilkS" user "Ref Des/Silkscreen Top")
		(7 "B.SilkS" user "Ref Des/Silkscreen Bottom")
		(1 "F.Mask" user "Board Geometry/Soldermask Top")
		(3 "B.Mask" user "Board Geometry/Soldermask Bottom")
		(17 "Dwgs.User" user "User.Drawings")
		(19 "Cmts.User" user "User.Comments")
		(21 "Eco1.User" user "User.Eco1")
		(23 "Eco2.User" user "User.Eco2")
		(25 "Edge.Cuts" user "Board Geometry/Outline")
		(27 "Margin" user)
		(31 "F.CrtYd" user "Package Geometry/Place Bound Top")
		(29 "B.CrtYd" user "Package Geometry/Place Bound Bottom")
		(35 "F.Fab" user "Ref Des/Assembly Top")
		(33 "B.Fab" user "Ref Des/Assembly Bottom")
	)
	(footprint ""
		(layer "F.Cu")
		(at 421.901874 -5.569966 -90)
		(property "Reference" "J37"
			(at -16.985996 31.63951 0)
			(unlocked yes)
			(layer "F.SilkS")
			(effects
				(font
					(size 0.7874 0.5842)
					(thickness 0.1524)
				)
				(justify left)
			)
		)
		(property "Value" ""
			(at 0 0 270)
			(layer "F.Fab")
			(effects
				(font
					(size 1.27 1.27)
				)
			)
		)
		(duplicate_pad_numbers_are_jumpers no)
		(pad "" np_thru_hole circle
			(at -0.599948 -32.079946 180)
			(size 1.1176 1.1176)
			(drill 1.1176)
			(layers "*.Cu" "*.Mask")
			(clearance 0.381)
			(thermal_gap 0.381)
		)
		(pad "" np_thru_hole circle
			(at 0.40005 32.085026 180)
			(size 1.1176 1.1176)
			(drill 1.1176)
			(layers "*.Cu" "*.Mask")
			(clearance 0.381)
			(thermal_gap 0.381)
		)
		(pad "A1" smd rect
			(at -2.750058 -18.465038 180)
			(size 0.381 1.4478)
			(layers "F.Cu" "F.Mask" "F.Paste")
			(net "GND")
		)
		(pad "A2" smd rect
			(at -2.750058 -17.86509 180)
			(size 0.381 1.4478)
			(layers "F.Cu" "F.Mask" "F.Paste")
			(net "GND")
		)
		(pad "A3" smd rect
			(at -2.750058 -17.264888 180)
			(size 0.381 1.4478)
			(layers "F.Cu" "F.Mask" "F.Paste")
			(net "GND")
		)
		(pad "A4" smd rect
			(at -2.750058 -16.66494 180)
			(size 0.381 1.4478)
			(layers "F.Cu" "F.Mask" "F.Paste")
			(net "GND")
		)
		(pad "A5" smd rect
			(at -2.750058 -16.064992 180)
			(size 0.381 1.4478)
			(layers "F.Cu" "F.Mask" "F.Paste")
			(net "GND")
		)
		(pad "A6" smd rect
			(at -2.750058 -15.465044 180)
			(size 0.381 1.4478)
			(layers "F.Cu" "F.Mask" "F.Paste")
			(net "GND")
		)
		(pad "A7" smd rect
			(at -2.750058 -14.865096 180)
			(size 0.381 1.4478)
			(layers "F.Cu" "F.Mask" "F.Paste")
			(net "SMB_OCP_SFF_3V3AUX_BUF_R_SCL")
		)
		(pad "A8" smd rect
			(at -2.750058 -14.264894 180)
			(size 0.381 1.4478)
			(layers "F.Cu" "F.Mask" "F.Paste")
			(net "SMB_OCP_SFF_3V3AUX_BUF_R_SDA")
		)
		(pad "A9" smd rect
			(at -2.750058 -13.664946 180)
			(size 0.381 1.4478)
			(layers "F.Cu" "F.Mask" "F.Paste")
			(net "RST_SMB_OCP_SFF_N")
		)
		(pad "A10" smd rect
			(at -2.750058 -13.064998 180)
			(size 0.381 1.4478)
			(layers "F.Cu" "F.Mask" "F.Paste")
			(net "OCP_SFF_PRSNTA_R_N")
		)
		(pad "A11" smd rect
			(at -2.750058 -12.46505 180)
			(size 0.381 1.4478)
			(layers "F.Cu" "F.Mask" "F.Paste")
			(net "RST_PERST1_OCP_SFF_N")
		)
		(pad "A12" smd rect
			(at -2.750058 -11.865102 180)
			(size 0.381 1.4478)
			(layers "F.Cu" "F.Mask" "F.Paste")
			(net "OCP_SFF_PRSNT2_R_N")
		)
		(pad "A13" smd rect
			(at -2.750058 -11.2649 180)
			(size 0.381 1.4478)
			(layers "F.Cu" "F.Mask" "F.Paste")
			(net "GND")
		)
		(pad "A14" smd rect
			(at -2.750058 -10.664952 180)
			(size 0.381 1.4478)
			(layers "F.Cu" "F.Mask" "F.Paste")
			(net "CLK_100M_OCP_SFF_1_DN")
		)
		(pad "A15" smd rect
			(at -2.750058 -10.065004 180)
			(size 0.381 1.4478)
			(layers "F.Cu" "F.Mask" "F.Paste")
			(net "CLK_100M_OCP_SFF_1_DP")
		)
		(pad "A16" smd rect
			(at -2.750058 -9.465056 180)
			(size 0.381 1.4478)
			(layers "F.Cu" "F.Mask" "F.Paste")
			(net "GND")
		)
		(pad "A17" smd rect
			(at -2.750058 -8.865108 180)
			(size 0.381 1.4478)
			(layers "F.Cu" "F.Mask" "F.Paste")
			(net "P5E_CPU0_PE1_RX_DN<0>")
		)
		(pad "A18" smd rect
			(at -2.750058 -8.264906 180)
			(size 0.381 1.4478)
			(layers "F.Cu" "F.Mask" "F.Paste")
			(net "P5E_CPU0_PE1_RX_DP<0>")
		)
		(pad "A19" smd rect
			(at -2.750058 -7.664958 180)
			(size 0.381 1.4478)
			(layers "F.Cu" "F.Mask" "F.Paste")
			(net "GND")
		)
		(pad "A20" smd rect
			(at -2.750058 -7.06501 180)
			(size 0.381 1.4478)
			(layers "F.Cu" "F.Mask" "F.Paste")
			(net "P5E_CPU0_PE1_RX_DP<1>")
		)
		(pad "A21" smd rect
			(at -2.750058 -6.465062 180)
			(size 0.381 1.4478)
			(layers "F.Cu" "F.Mask" "F.Paste")
			(net "P5E_CPU0_PE1_RX_DN<1>")
		)
		(pad "A22" smd rect
			(at -2.750058 -5.865114 180)
			(size 0.381 1.4478)
			(layers "F.Cu" "F.Mask" "F.Paste")
			(net "GND")
		)
		(pad "A23" smd rect
			(at -2.750058 -5.264912 180)
			(size 0.381 1.4478)
			(layers "F.Cu" "F.Mask" "F.Paste")
			(net "P5E_CPU0_PE1_RX_DP<2>")
		)
		(pad "A24" smd rect
			(at -2.750058 -4.664964 180)
			(size 0.381 1.4478)
			(layers "F.Cu" "F.Mask" "F.Paste")
			(net "P5E_CPU0_PE1_RX_DN<2>")
		)
		(pad "A25" smd rect
			(at -2.750058 -4.065016 180)
			(size 0.381 1.4478)
			(layers "F.Cu" "F.Mask" "F.Paste")
			(net "GND")
		)
		(pad "A26" smd rect
			(at -2.750058 -3.465068 180)
			(size 0.381 1.4478)
			(layers "F.Cu" "F.Mask" "F.Paste")
			(net "P5E_CPU0_PE1_RX_DP<3>")
		)
		(pad "A27" smd rect
			(at -2.750058 -2.86512 180)
			(size 0.381 1.4478)
			(layers "F.Cu" "F.Mask" "F.Paste")
			(net "P5E_CPU0_PE1_RX_DN<3>")
		)
		(pad "A28" smd rect
			(at -2.750058 -2.264918 180)
			(size 0.381 1.4478)
			(layers "F.Cu" "F.Mask" "F.Paste")
			(net "GND")
		)
		(pad "A29" smd rect
			(at -2.750058 1.74498 180)
			(size 0.381 1.4478)
			(layers "F.Cu" "F.Mask" "F.Paste")
			(net "GND")
		)
		(pad "A30" smd rect
			(at -2.750058 2.344928 180)
			(size 0.381 1.4478)
			(layers "F.Cu" "F.Mask" "F.Paste")
			(net "P5E_CPU0_PE1_RX_DP<4>")
		)
		(pad "A31" smd rect
			(at -2.750058 2.944876 180)
			(size 0.381 1.4478)
			(layers "F.Cu" "F.Mask" "F.Paste")
			(net "P5E_CPU0_PE1_RX_DN<4>")
		)
		(pad "A32" smd rect
			(at -2.750058 3.545078 180)
			(size 0.381 1.4478)
			(layers "F.Cu" "F.Mask" "F.Paste")
			(net "GND")
		)
		(pad "A33" smd rect
			(at -2.750058 4.145026 180)
			(size 0.381 1.4478)
			(layers "F.Cu" "F.Mask" "F.Paste")
			(net "P5E_CPU0_PE1_RX_DP<5>")
		)
		(pad "A34" smd rect
			(at -2.750058 4.744974 180)
			(size 0.381 1.4478)
			(layers "F.Cu" "F.Mask" "F.Paste")
			(net "P5E_CPU0_PE1_RX_DN<5>")
		)
		(pad "A35" smd rect
			(at -2.750058 5.344922 180)
			(size 0.381 1.4478)
			(layers "F.Cu" "F.Mask" "F.Paste")
			(net "GND")
		)
		(pad "A36" smd rect
			(at -2.750058 5.945124 180)
			(size 0.381 1.4478)
			(layers "F.Cu" "F.Mask" "F.Paste")
			(net "P5E_CPU0_PE1_RX_DP<6>")
		)
		(pad "A37" smd rect
			(at -2.750058 6.545072 180)
			(size 0.381 1.4478)
			(layers "F.Cu" "F.Mask" "F.Paste")
			(net "P5E_CPU0_PE1_RX_DN<6>")
		)
		(pad "A38" smd rect
			(at -2.750058 7.14502 180)
			(size 0.381 1.4478)
			(layers "F.Cu" "F.Mask" "F.Paste")
			(net "GND")
		)
		(pad "A39" smd rect
			(at -2.750058 7.744968 180)
			(size 0.381 1.4478)
			(layers "F.Cu" "F.Mask" "F.Paste")
			(net "P5E_CPU0_PE1_RX_DP<7>")
		)
		(pad "A40" smd rect
			(at -2.750058 8.344916 180)
			(size 0.381 1.4478)
			(layers "F.Cu" "F.Mask" "F.Paste")
			(net "P5E_CPU0_PE1_RX_DN<7>")
		)
		(pad "A41" smd rect
			(at -2.750058 8.945118 180)
			(size 0.381 1.4478)
			(layers "F.Cu" "F.Mask" "F.Paste")
			(net "GND")
		)
		(pad "A42" smd rect
			(at -2.750058 9.545066 180)
			(size 0.381 1.4478)
			(layers "F.Cu" "F.Mask" "F.Paste")
			(net "OCP_SFF_PRSNT1_R_N")
		)
		(pad "A43" smd rect
			(at -2.750058 14.454886 180)
			(size 0.381 1.4478)
			(layers "F.Cu" "F.Mask" "F.Paste")
			(net "GND")
		)
		(pad "A44" smd rect
			(at -2.750058 15.055088 180)
			(size 0.381 1.4478)
			(layers "F.Cu" "F.Mask" "F.Paste")
			(net "P5E_CPU0_PE1_RX_DP<8>")
		)
		(pad "A45" smd rect
			(at -2.750058 15.655036 180)
			(size 0.381 1.4478)
			(layers "F.Cu" "F.Mask" "F.Paste")
			(net "P5E_CPU0_PE1_RX_DN<8>")
		)
		(pad "A46" smd rect
			(at -2.750058 16.254984 180)
			(size 0.381 1.4478)
			(layers "F.Cu" "F.Mask" "F.Paste")
			(net "GND")
		)
		(pad "A47" smd rect
			(at -2.750058 16.854932 180)
			(size 0.381 1.4478)
			(layers "F.Cu" "F.Mask" "F.Paste")
			(net "P5E_CPU0_PE1_RX_DP<9>")
		)
		(pad "A48" smd rect
			(at -2.750058 17.45488 180)
			(size 0.381 1.4478)
			(layers "F.Cu" "F.Mask" "F.Paste")
			(net "P5E_CPU0_PE1_RX_DN<9>")
		)
		(pad "A49" smd rect
			(at -2.750058 18.055082 180)
			(size 0.381 1.4478)
			(layers "F.Cu" "F.Mask" "F.Paste")
			(net "GND")
		)
		(pad "A50" smd rect
			(at -2.750058 18.65503 180)
			(size 0.381 1.4478)
			(layers "F.Cu" "F.Mask" "F.Paste")
			(net "P5E_CPU0_PE1_RX_DP<10>")
		)
		(pad "A51" smd rect
			(at -2.750058 19.254978 180)
			(size 0.381 1.4478)
			(layers "F.Cu" "F.Mask" "F.Paste")
			(net "P5E_CPU0_PE1_RX_DN<10>")
		)
		(pad "A52" smd rect
			(at -2.750058 19.854926 180)
			(size 0.381 1.4478)
			(layers "F.Cu" "F.Mask" "F.Paste")
			(net "GND")
		)
		(pad "A53" smd rect
			(at -2.750058 20.455128 180)
			(size 0.381 1.4478)
			(layers "F.Cu" "F.Mask" "F.Paste")
			(net "P5E_CPU0_PE1_RX_DP<11>")
		)
		(pad "A54" smd rect
			(at -2.750058 21.055076 180)
			(size 0.381 1.4478)
			(layers "F.Cu" "F.Mask" "F.Paste")
			(net "P5E_CPU0_PE1_RX_DN<11>")
		)
		(pad "A55" smd rect
			(at -2.750058 21.655024 180)
			(size 0.381 1.4478)
			(layers "F.Cu" "F.Mask" "F.Paste")
			(net "GND")
		)
		(pad "A56" smd rect
			(at -2.750058 22.254972 180)
			(size 0.381 1.4478)
			(layers "F.Cu" "F.Mask" "F.Paste")
			(net "P5E_CPU0_PE1_RX_DP<12>")
		)
		(pad "A57" smd rect
			(at -2.750058 22.85492 180)
			(size 0.381 1.4478)
			(layers "F.Cu" "F.Mask" "F.Paste")
			(net "P5E_CPU0_PE1_RX_DN<12>")
		)
		(pad "A58" smd rect
			(at -2.750058 23.455122 180)
			(size 0.381 1.4478)
			(layers "F.Cu" "F.Mask" "F.Paste")
			(net "GND")
		)
		(pad "A59" smd rect
			(at -2.750058 24.05507 180)
			(size 0.381 1.4478)
			(layers "F.Cu" "F.Mask" "F.Paste")
			(net "P5E_CPU0_PE1_RX_DP<13>")
		)
		(pad "A60" smd rect
			(at -2.750058 24.655018 180)
			(size 0.381 1.4478)
			(layers "F.Cu" "F.Mask" "F.Paste")
			(net "P5E_CPU0_PE1_RX_DN<13>")
		)
		(pad "A61" smd rect
			(at -2.750058 25.254966 180)
			(size 0.381 1.4478)
			(layers "F.Cu" "F.Mask" "F.Paste")
			(net "GND")
		)
		(pad "A62" smd rect
			(at -2.750058 25.854914 180)
			(size 0.381 1.4478)
			(layers "F.Cu" "F.Mask" "F.Paste")
			(net "P5E_CPU0_PE1_RX_DP<14>")
		)
		(pad "A63" smd rect
			(at -2.750058 26.455116 180)
			(size 0.381 1.4478)
			(layers "F.Cu" "F.Mask" "F.Paste")
			(net "P5E_CPU0_PE1_RX_DN<14>")
		)
		(pad "A64" smd rect
			(at -2.750058 27.055064 180)
			(size 0.381 1.4478)
			(layers "F.Cu" "F.Mask" "F.Paste")
			(net "GND")
		)
		(pad "A65" smd rect
			(at -2.750058 27.655012 180)
			(size 0.381 1.4478)
			(layers "F.Cu" "F.Mask" "F.Paste")
			(net "P5E_CPU0_PE1_RX_DP<15>")
		)
		(pad "A66" smd rect
			(at -2.750058 28.25496 180)
			(size 0.381 1.4478)
			(layers "F.Cu" "F.Mask" "F.Paste")
			(net "P5E_CPU0_PE1_RX_DN<15>")
		)
		(pad "A67" smd rect
			(at -2.750058 28.854908 180)
			(size 0.381 1.4478)
			(layers "F.Cu" "F.Mask" "F.Paste")
			(net "GND")
		)
		(pad "A68" smd rect
			(at -2.750058 29.45511 180)
			(size 0.381 1.4478)
			(layers "F.Cu" "F.Mask" "F.Paste")
			(net "OCP_SFF_USB2_3_DN")
		)
		(pad "A69" smd rect
			(at -2.750058 30.055058 180)
			(size 0.381 1.4478)
			(layers "F.Cu" "F.Mask" "F.Paste")
			(net "OCP_SFF_USB2_3_DP")
		)
		(pad "A70" smd rect
			(at -2.750058 30.655006 180)
			(size 0.381 1.4478)
			(layers "F.Cu" "F.Mask" "F.Paste")
			(net "OCP_SFF_PWRBRK_N")
		)
		(pad "B1" smd rect
			(at -5.700014 -18.465038 180)
			(size 0.381 1.4478)
			(layers "F.Cu" "F.Mask" "F.Paste")
			(net "P12V_OCP_SFF")
		)
		(pad "B2" smd rect
			(at -5.700014 -17.86509 180)
			(size 0.381 1.4478)
			(layers "F.Cu" "F.Mask" "F.Paste")
			(net "P12V_OCP_SFF")
		)
		(pad "B3" smd rect
			(at -5.700014 -17.264888 180)
			(size 0.381 1.4478)
			(layers "F.Cu" "F.Mask" "F.Paste")
			(net "P12V_OCP_SFF")
		)
		(pad "B4" smd rect
			(at -5.700014 -16.66494 180)
			(size 0.381 1.4478)
			(layers "F.Cu" "F.Mask" "F.Paste")
			(net "P12V_OCP_SFF")
		)
		(pad "B5" smd rect
			(at -5.700014 -16.064992 180)
			(size 0.381 1.4478)
			(layers "F.Cu" "F.Mask" "F.Paste")
			(net "P12V_OCP_SFF")
		)
		(pad "B6" smd rect
			(at -5.700014 -15.465044 180)
			(size 0.381 1.4478)
			(layers "F.Cu" "F.Mask" "F.Paste")
			(net "P12V_OCP_SFF")
		)
		(pad "B7" smd rect
			(at -5.700014 -14.865096 180)
			(size 0.381 1.4478)
			(layers "F.Cu" "F.Mask" "F.Paste")
			(net "OCP_SFF_BIF0_R_N")
		)
		(pad "B8" smd rect
			(at -5.700014 -14.264894 180)
			(size 0.381 1.4478)
			(layers "F.Cu" "F.Mask" "F.Paste")
			(net "OCP_SFF_BIF1_R_N")
		)
		(pad "B9" smd rect
			(at -5.700014 -13.664946 180)
			(size 0.381 1.4478)
			(layers "F.Cu" "F.Mask" "F.Paste")
			(net "OCP_SFF_BIF2_R_N")
		)
		(pad "B10" smd rect
			(at -5.700014 -13.064998 180)
			(size 0.381 1.4478)
			(layers "F.Cu" "F.Mask" "F.Paste")
			(net "RST_PERST0_OCP_SFF_N")
		)
		(pad "B11" smd rect
			(at -5.700014 -12.46505 180)
			(size 0.381 1.4478)
			(layers "F.Cu" "F.Mask" "F.Paste")
			(net "P3V3_OCP_SFF")
		)
		(pad "B12" smd rect
			(at -5.700014 -11.865102 180)
			(size 0.381 1.4478)
			(layers "F.Cu" "F.Mask" "F.Paste")
			(net "OCP_SFF_AUX_PWR_EN_R")
		)
		(pad "B13" smd rect
			(at -5.700014 -11.2649 180)
			(size 0.381 1.4478)
			(layers "F.Cu" "F.Mask" "F.Paste")
			(net "GND")
		)
		(pad "B14" smd rect
			(at -5.700014 -10.664952 180)
			(size 0.381 1.4478)
			(layers "F.Cu" "F.Mask" "F.Paste")
			(net "CLK_100M_OCP_SFF_0_DN")
		)
		(pad "B15" smd rect
			(at -5.700014 -10.065004 180)
			(size 0.381 1.4478)
			(layers "F.Cu" "F.Mask" "F.Paste")
			(net "CLK_100M_OCP_SFF_0_DP")
		)
		(pad "B16" smd rect
			(at -5.700014 -9.465056 180)
			(size 0.381 1.4478)
			(layers "F.Cu" "F.Mask" "F.Paste")
			(net "GND")
		)
		(pad "B17" smd rect
			(at -5.700014 -8.865108 180)
			(size 0.381 1.4478)
			(layers "F.Cu" "F.Mask" "F.Paste")
			(net "P5E_CPU0_PE1_TX_C_DN<0>")
		)
		(pad "B18" smd rect
			(at -5.700014 -8.264906 180)
			(size 0.381 1.4478)
			(layers "F.Cu" "F.Mask" "F.Paste")
			(net "P5E_CPU0_PE1_TX_C_DP<0>")
		)
		(pad "B19" smd rect
			(at -5.700014 -7.664958 180)
			(size 0.381 1.4478)
			(layers "F.Cu" "F.Mask" "F.Paste")
			(net "GND")
		)
		(pad "B20" smd rect
			(at -5.700014 -7.06501 180)
			(size 0.381 1.4478)
			(layers "F.Cu" "F.Mask" "F.Paste")
			(net "P5E_CPU0_PE1_TX_C_DN<1>")
		)
		(pad "B21" smd rect
			(at -5.700014 -6.465062 180)
			(size 0.381 1.4478)
			(layers "F.Cu" "F.Mask" "F.Paste")
			(net "P5E_CPU0_PE1_TX_C_DP<1>")
		)
		(pad "B22" smd rect
			(at -5.700014 -5.865114 180)
			(size 0.381 1.4478)
			(layers "F.Cu" "F.Mask" "F.Paste")
			(net "GND")
		)
		(pad "B23" smd rect
			(at -5.700014 -5.264912 180)
			(size 0.381 1.4478)
			(layers "F.Cu" "F.Mask" "F.Paste")
			(net "P5E_CPU0_PE1_TX_C_DP<2>")
		)
		(pad "B24" smd rect
			(at -5.700014 -4.664964 180)
			(size 0.381 1.4478)
			(layers "F.Cu" "F.Mask" "F.Paste")
			(net "P5E_CPU0_PE1_TX_C_DN<2>")
		)
		(pad "B25" smd rect
			(at -5.700014 -4.065016 180)
			(size 0.381 1.4478)
			(layers "F.Cu" "F.Mask" "F.Paste")
			(net "GND")
		)
		(pad "B26" smd rect
			(at -5.700014 -3.465068 180)
			(size 0.381 1.4478)
			(layers "F.Cu" "F.Mask" "F.Paste")
			(net "P5E_CPU0_PE1_TX_C_DN<3>")
		)
		(pad "B27" smd rect
			(at -5.700014 -2.86512 180)
			(size 0.381 1.4478)
			(layers "F.Cu" "F.Mask" "F.Paste")
			(net "P5E_CPU0_PE1_TX_C_DP<3>")
		)
		(pad "B28" smd rect
			(at -5.700014 -2.264918 180)
			(size 0.381 1.4478)
			(layers "F.Cu" "F.Mask" "F.Paste")
			(net "GND")
		)
		(pad "B29" smd rect
			(at -5.700014 1.74498 180)
			(size 0.381 1.4478)
			(layers "F.Cu" "F.Mask" "F.Paste")
			(net "GND")
		)
		(pad "B30" smd rect
			(at -5.700014 2.344928 180)
			(size 0.381 1.4478)
			(layers "F.Cu" "F.Mask" "F.Paste")
			(net "P5E_CPU0_PE1_TX_C_DP<4>")
		)
		(pad "B31" smd rect
			(at -5.700014 2.944876 180)
			(size 0.381 1.4478)
			(layers "F.Cu" "F.Mask" "F.Paste")
			(net "P5E_CPU0_PE1_TX_C_DN<4>")
		)
		(pad "B32" smd rect
			(at -5.700014 3.545078 180)
			(size 0.381 1.4478)
			(layers "F.Cu" "F.Mask" "F.Paste")
			(net "GND")
		)
		(pad "B33" smd rect
			(at -5.700014 4.145026 180)
			(size 0.381 1.4478)
			(layers "F.Cu" "F.Mask" "F.Paste")
			(net "P5E_CPU0_PE1_TX_C_DN<5>")
		)
		(pad "B34" smd rect
			(at -5.700014 4.744974 180)
			(size 0.381 1.4478)
			(layers "F.Cu" "F.Mask" "F.Paste")
			(net "P5E_CPU0_PE1_TX_C_DP<5>")
		)
		(pad "B35" smd rect
			(at -5.700014 5.344922 180)
			(size 0.381 1.4478)
			(layers "F.Cu" "F.Mask" "F.Paste")
			(net "GND")
		)
		(pad "B36" smd rect
			(at -5.700014 5.945124 180)
			(size 0.381 1.4478)
			(layers "F.Cu" "F.Mask" "F.Paste")
			(net "P5E_CPU0_PE1_TX_C_DP<6>")
		)
		(pad "B37" smd rect
			(at -5.700014 6.545072 180)
			(size 0.381 1.4478)
			(layers "F.Cu" "F.Mask" "F.Paste")
			(net "P5E_CPU0_PE1_TX_C_DN<6>")
		)
	)
)
